(kicad_pcb
	(version 20260206)
	(generator "pcbnew")
	(generator_version "10.0")
	(general
		(thickness 1.6)
		(legacy_teardrops no)
	)
	(paper "A4")
	(title_block
		(title "04192023_DAF0TMB3IC0_F0TG_MB_C_brd_V02_OCP.brd")
		(comment 1 "Grand Teton / footprints 1696-1701 of 8354")
	)
	(layers
		(0 "F.Cu" signal "TOP")
		(4 "In1.Cu" signal "GND")
		(6 "In2.Cu" signal "IN1")
		(8 "In3.Cu" signal "GND1")
		(10 "In4.Cu" signal "IN2")
		(12 "In5.Cu" signal "GND2")
		(14 "In6.Cu" signal "IN3")
		(16 "In7.Cu" signal "GND3")
		(18 "In8.Cu" signal "VCC")
		(20 "In9.Cu" signal "VCC1")
		(22 "In10.Cu" signal "GND4")
		(24 "In11.Cu" signal "IN4")
		(26 "In12.Cu" signal "GND5")
		(28 "In13.Cu" signal "IN5")
		(30 "In14.Cu" signal "GND6")
		(32 "In15.Cu" signal "IN6")
		(34 "In16.Cu" signal "GND7")
		(2 "B.Cu" signal "BOTTOM")
		(9 "F.Adhes" user "F.Adhesive")
		(11 "B.Adhes" user "B.Adhesive")
		(13 "F.Paste" user "Package Geometry/Pastemask Top")
		(15 "B.Paste" user "Package Geometry/Pastemask Bottom")
		(5 "F.SilkS" user "Ref Des/Silkscreen Top")
		(7 "B.SilkS" user "Ref Des/Silkscreen Bottom")
		(1 "F.Mask" user "Board Geometry/Soldermask Top")
		(3 "B.Mask" user "Board Geometry/Soldermask Bottom")
		(17 "Dwgs.User" user "User.Drawings")
		(19 "Cmts.User" user "User.Comments")
		(21 "Eco1.User" user "User.Eco1")
		(23 "Eco2.User" user "User.Eco2")
		(25 "Edge.Cuts" user "Board Geometry/Outline")
		(27 "Margin" user)
		(31 "F.CrtYd" user "Package Geometry/Place Bound Top")
		(29 "B.CrtYd" user "Package Geometry/Place Bound Bottom")
		(35 "F.Fab" user "Ref Des/Assembly Top")
		(33 "B.Fab" user "Ref Des/Assembly Bottom")
	)
	(footprint ""
		(layer "F.Cu")
		(at 74.04354 -335.099406 -90)
		(property "Reference" "PC406_3"
			(at 0 0 270)
			(layer "F.SilkS")
			(hide yes)
			(effects
				(font
					(size 1.27 1.27)
				)
			)
		)
		(property "Value" ""
			(at 0 0 270)
			(layer "F.Fab")
			(effects
				(font
					(size 1.27 1.27)
				)
			)
		)
		(duplicate_pad_numbers_are_jumpers no)
		(fp_line
			(start -0.7874 0.4064)
			(end -0.7874 -0.4064)
			(stroke
				(width 0.1524)
				(type default)
			)
			(layer "F.SilkS")
		)
		(fp_line
			(start 0.7874 0.4064)
			(end -0.7874 0.4064)
			(stroke
				(width 0.1524)
				(type default)
			)
			(layer "F.SilkS")
		)
		(fp_line
			(start -0.7874 -0.4064)
			(end 0.7874 -0.4064)
			(stroke
				(width 0.1524)
				(type default)
			)
			(layer "F.SilkS")
		)
		(fp_line
			(start 0.7874 -0.4064)
			(end 0.7874 0.4064)
			(stroke
				(width 0.1524)
				(type default)
			)
			(layer "F.SilkS")
		)
		(fp_line
			(start -0.67945 0.3048)
			(end -0.67945 -0.305054)
			(stroke
				(width 0.1)
				(type default)
			)
			(layer "F.Fab")
		)
		(fp_line
			(start -0.12065 0.3048)
			(end -0.67945 0.3048)
			(stroke
				(width 0.1)
				(type default)
			)
			(layer "F.Fab")
		)
		(fp_line
			(start 0.120396 0.3048)
			(end 0.120396 0.2794)
			(stroke
				(width 0.1)
				(type default)
			)
			(layer "F.Fab")
		)
		(fp_line
			(start 0.67945 0.3048)
			(end 0.120396 0.3048)
			(stroke
				(width 0.1)
				(type default)
			)
			(layer "F.Fab")
		)
		(fp_line
			(start -0.12065 0.2794)
			(end -0.12065 0.3048)
			(stroke
				(width 0.1)
				(type default)
			)
			(layer "F.Fab")
		)
		(fp_line
			(start 0.120396 0.2794)
			(end -0.12065 0.2794)
			(stroke
				(width 0.1)
				(type default)
			)
			(layer "F.Fab")
		)
		(fp_line
			(start -0.12065 -0.2794)
			(end 0.12065 -0.2794)
			(stroke
				(width 0.1)
				(type default)
			)
			(layer "F.Fab")
		)
		(fp_line
			(start 0.12065 -0.2794)
			(end 0.12065 -0.3048)
			(stroke
				(width 0.1)
				(type default)
			)
			(layer "F.Fab")
		)
		(fp_line
			(start 0.12065 -0.3048)
			(end 0.67945 -0.3048)
			(stroke
				(width 0.1)
				(type default)
			)
			(layer "F.Fab")
		)
		(fp_line
			(start 0.67945 -0.3048)
			(end 0.67945 0.3048)
			(stroke
				(width 0.1)
				(type default)
			)
			(layer "F.Fab")
		)
		(fp_line
			(start -0.67945 -0.305054)
			(end -0.12065 -0.305054)
			(stroke
				(width 0.1)
				(type default)
			)
			(layer "F.Fab")
		)
		(fp_line
			(start -0.12065 -0.305054)
			(end -0.12065 -0.2794)
			(stroke
				(width 0.1)
				(type default)
			)
			(layer "F.Fab")
		)
		(pad "1" smd circle
			(at -0.40005 0 270)
			(size 0 0)
			(layers "F.Cu" "F.Mask" "F.Paste")
			(net "SW_P12V_AUX_PVDDCR_CPU1_P1_FLT")
		)
		(pad "2" smd circle
			(at 0.40005 0 270)
			(size 0 0)
			(layers "F.Cu" "F.Mask" "F.Paste")
			(net "GND")
		)
	)
	(footprint ""
		(layer "F.Cu")
		(at 341.648542 -356.05339 90)
		(property "Reference" "PL12"
			(at -1.4224 3.870452 90)
			(unlocked yes)
			(layer "F.SilkS")
			(effects
				(font
					(size 0.7874 0.5842)
					(thickness 0.1524)
				)
				(justify left)
			)
		)
		(property "Value" ""
			(at 0 0 90)
			(layer "F.Fab")
			(effects
				(font
					(size 1.27 1.27)
				)
			)
		)
		(duplicate_pad_numbers_are_jumpers no)
		(fp_line
			(start 3.050032 -2.999994)
			(end -3.050032 -2.999994)
			(stroke
				(width 0.1524)
				(type default)
			)
			(layer "F.SilkS")
		)
		(fp_line
			(start -3.050032 -2.999994)
			(end -3.050032 -1.4478)
			(stroke
				(width 0.1524)
				(type default)
			)
			(layer "F.SilkS")
		)
		(fp_line
			(start 3.050032 -1.4478)
			(end 3.050032 -2.999994)
			(stroke
				(width 0.1524)
				(type default)
			)
			(layer "F.SilkS")
		)
		(fp_line
			(start -3.050032 1.4478)
			(end -3.050032 2.999994)
			(stroke
				(width 0.1524)
				(type default)
			)
			(layer "F.SilkS")
		)
		(fp_line
			(start 3.050032 2.999994)
			(end 3.050032 1.4478)
			(stroke
				(width 0.1524)
				(type default)
			)
			(layer "F.SilkS")
		)
		(fp_line
			(start -3.050032 2.999994)
			(end 3.050032 2.999994)
			(stroke
				(width 0.1524)
				(type default)
			)
			(layer "F.SilkS")
		)
		(fp_line
			(start 3.050032 -2.999994)
			(end -3.050032 -2.999994)
			(stroke
				(width 0.1)
				(type default)
			)
			(layer "F.Fab")
		)
		(fp_line
			(start -3.050032 -2.999994)
			(end -3.050032 2.999994)
			(stroke
				(width 0.1)
				(type default)
			)
			(layer "F.Fab")
		)
		(fp_line
			(start 3.050032 2.999994)
			(end 3.050032 -2.999994)
			(stroke
				(width 0.1)
				(type default)
			)
			(layer "F.Fab")
		)
		(fp_line
			(start -3.050032 2.999994)
			(end 3.050032 2.999994)
			(stroke
				(width 0.1)
				(type default)
			)
			(layer "F.Fab")
		)
		(pad "1" smd rect
			(at -2.525014 0 90)
			(size 1.651 2.6162)
			(layers "F.Cu" "F.Mask" "F.Paste")
			(net "SW_P12V_AUX_PVDDCR_CPU1_P0_FLT")
		)
		(pad "2" smd rect
			(at 2.525014 0 90)
			(size 1.651 2.6162)
			(layers "F.Cu" "F.Mask" "F.Paste")
			(net "P12V_AUX")
		)
	)
	(footprint ""
		(layer "F.Cu")
		(at 179.961286 -133.43763 -90)
		(property "Reference" "R6741"
			(at 0 0 270)
			(layer "F.SilkS")
			(hide yes)
			(effects
				(font
					(size 1.27 1.27)
				)
			)
		)
		(property "Value" ""
			(at 0 0 270)
			(layer "F.Fab")
			(effects
				(font
					(size 1.27 1.27)
				)
			)
		)
		(duplicate_pad_numbers_are_jumpers no)
		(fp_line
			(start -0.7874 0.4064)
			(end -0.7874 -0.4064)
			(stroke
				(width 0.1524)
				(type default)
			)
			(layer "F.SilkS")
		)
		(fp_line
			(start 0.7874 0.4064)
			(end -0.7874 0.4064)
			(stroke
				(width 0.1524)
				(type default)
			)
			(layer "F.SilkS")
		)
		(fp_line
			(start -0.7874 -0.4064)
			(end 0.7874 -0.4064)
			(stroke
				(width 0.1524)
				(type default)
			)
			(layer "F.SilkS")
		)
		(fp_line
			(start 0.7874 -0.4064)
			(end 0.7874 0.4064)
			(stroke
				(width 0.1524)
				(type default)
			)
			(layer "F.SilkS")
		)
		(fp_line
			(start -0.67945 0.3048)
			(end -0.67945 -0.305054)
			(stroke
				(width 0.1)
				(type default)
			)
			(layer "F.Fab")
		)
		(fp_line
			(start -0.12065 0.3048)
			(end -0.67945 0.3048)
			(stroke
				(width 0.1)
				(type default)
			)
			(layer "F.Fab")
		)
		(fp_line
			(start 0.120396 0.3048)
			(end 0.120396 0.2794)
			(stroke
				(width 0.1)
				(type default)
			)
			(layer "F.Fab")
		)
		(fp_line
			(start 0.67945 0.3048)
			(end 0.120396 0.3048)
			(stroke
				(width 0.1)
				(type default)
			)
			(layer "F.Fab")
		)
		(fp_line
			(start -0.12065 0.2794)
			(end -0.12065 0.3048)
			(stroke
				(width 0.1)
				(type default)
			)
			(layer "F.Fab")
		)
		(fp_line
			(start 0.120396 0.2794)
			(end -0.12065 0.2794)
			(stroke
				(width 0.1)
				(type default)
			)
			(layer "F.Fab")
		)
		(fp_line
			(start -0.12065 -0.2794)
			(end 0.12065 -0.2794)
			(stroke
				(width 0.1)
				(type default)
			)
			(layer "F.Fab")
		)
		(fp_line
			(start 0.12065 -0.2794)
			(end 0.12065 -0.3048)
			(stroke
				(width 0.1)
				(type default)
			)
			(layer "F.Fab")
		)
		(fp_line
			(start 0.12065 -0.3048)
			(end 0.67945 -0.3048)
			(stroke
				(width 0.1)
				(type default)
			)
			(layer "F.Fab")
		)
		(fp_line
			(start 0.67945 -0.3048)
			(end 0.67945 0.3048)
			(stroke
				(width 0.1)
				(type default)
			)
			(layer "F.Fab")
		)
		(fp_line
			(start -0.67945 -0.305054)
			(end -0.12065 -0.305054)
			(stroke
				(width 0.1)
				(type default)
			)
			(layer "F.Fab")
		)
		(fp_line
			(start -0.12065 -0.305054)
			(end -0.12065 -0.2794)
			(stroke
				(width 0.1)
				(type default)
			)
			(layer "F.Fab")
		)
		(pad "1" smd circle
			(at -0.40005 0 270)
			(size 0 0)
			(layers "F.Cu" "F.Mask" "F.Paste")
			(net "RST_RT_CPU1_P1_RESET_R_N")
		)
		(pad "2" smd circle
			(at 0.40005 0 270)
			(size 0 0)
			(layers "F.Cu" "F.Mask" "F.Paste")
			(net "RST_RT_CPU1_P1_RESET_R2_N")
		)
	)
	(footprint ""
		(layer "F.Cu")
		(at 123.835922 -13.99413 180)
		(property "Reference" "R4184"
			(at 0 0 180)
			(layer "F.SilkS")
			(hide yes)
			(effects
				(font
					(size 1.27 1.27)
				)
			)
		)
		(property "Value" ""
			(at 0 0 180)
			(layer "F.Fab")
			(effects
				(font
					(size 1.27 1.27)
				)
			)
		)
		(duplicate_pad_numbers_are_jumpers no)
		(fp_line
			(start 0.7874 0.4064)
			(end -0.7874 0.4064)
			(stroke
				(width 0.1524)
				(type default)
			)
			(layer "F.SilkS")
		)
		(fp_line
			(start 0.7874 -0.4064)
			(end 0.7874 0.4064)
			(stroke
				(width 0.1524)
				(type default)
			)
			(layer "F.SilkS")
		)
		(fp_line
			(start -0.7874 0.4064)
			(end -0.7874 -0.4064)
			(stroke
				(width 0.1524)
				(type default)
			)
			(layer "F.SilkS")
		)
		(fp_line
			(start -0.7874 -0.4064)
			(end 0.7874 -0.4064)
			(stroke
				(width 0.1524)
				(type default)
			)
			(layer "F.SilkS")
		)
		(fp_line
			(start 0.67945 0.3048)
			(end 0.120396 0.3048)
			(stroke
				(width 0.1)
				(type default)
			)
			(layer "F.Fab")
		)
		(fp_line
			(start 0.67945 -0.3048)
			(end 0.67945 0.3048)
			(stroke
				(width 0.1)
				(type default)
			)
			(layer "F.Fab")
		)
		(fp_line
			(start 0.12065 -0.2794)
			(end 0.12065 -0.3048)
			(stroke
				(width 0.1)
				(type default)
			)
			(layer "F.Fab")
		)
		(fp_line
			(start 0.12065 -0.3048)
			(end 0.67945 -0.3048)
			(stroke
				(width 0.1)
				(type default)
			)
			(layer "F.Fab")
		)
		(fp_line
			(start 0.120396 0.3048)
			(end 0.120396 0.2794)
			(stroke
				(width 0.1)
				(type default)
			)
			(layer "F.Fab")
		)
		(fp_line
			(start 0.120396 0.2794)
			(end -0.12065 0.2794)
			(stroke
				(width 0.1)
				(type default)
			)
			(layer "F.Fab")
		)
		(fp_line
			(start -0.12065 0.3048)
			(end -0.67945 0.3048)
			(stroke
				(width 0.1)
				(type default)
			)
			(layer "F.Fab")
		)
		(fp_line
			(start -0.12065 0.2794)
			(end -0.12065 0.3048)
			(stroke
				(width 0.1)
				(type default)
			)
			(layer "F.Fab")
		)
		(fp_line
			(start -0.12065 -0.2794)
			(end 0.12065 -0.2794)
			(stroke
				(width 0.1)
				(type default)
			)
			(layer "F.Fab")
		)
		(fp_line
			(start -0.12065 -0.305054)
			(end -0.12065 -0.2794)
			(stroke
				(width 0.1)
				(type default)
			)
			(layer "F.Fab")
		)
		(fp_line
			(start -0.67945 0.3048)
			(end -0.67945 -0.305054)
			(stroke
				(width 0.1)
				(type default)
			)
			(layer "F.Fab")
		)
		(fp_line
			(start -0.67945 -0.305054)
			(end -0.12065 -0.305054)
			(stroke
				(width 0.1)
				(type default)
			)
			(layer "F.Fab")
		)
		(pad "1" smd circle
			(at -0.40005 0 180)
			(size 0 0)
			(layers "F.Cu" "F.Mask" "F.Paste")
			(net "P3V3_AUX")
		)
		(pad "2" smd circle
			(at 0.40005 0 180)
			(size 0 0)
			(layers "F.Cu" "F.Mask" "F.Paste")
			(net "U273_3_ADD2")
		)
	)
	(footprint ""
		(layer "F.Cu")
		(at 166.3192 -431.3936)
		(property "Reference" "R2671"
			(at 0 0 0)
			(layer "F.SilkS")
			(hide yes)
			(effects
				(font
					(size 1.27 1.27)
				)
			)
		)
		(property "Value" ""
			(at 0 0 0)
			(layer "F.Fab")
			(effects
				(font
					(size 1.27 1.27)
				)
			)
		)
		(duplicate_pad_numbers_are_jumpers no)
		(fp_line
			(start -0.7874 -0.4064)
			(end 0.7874 -0.4064)
			(stroke
				(width 0.1524)
				(type default)
			)
			(layer "F.SilkS")
		)
		(fp_line
			(start -0.7874 0.4064)
			(end -0.7874 -0.4064)
			(stroke
				(width 0.1524)
				(type default)
			)
			(layer "F.SilkS")
		)
		(fp_line
			(start 0.7874 -0.4064)
			(end 0.7874 0.4064)
			(stroke
				(width 0.1524)
				(type default)
			)
			(layer "F.SilkS")
		)
		(fp_line
			(start 0.7874 0.4064)
			(end -0.7874 0.4064)
			(stroke
				(width 0.1524)
				(type default)
			)
			(layer "F.SilkS")
		)
		(fp_line
			(start -0.67945 -0.305054)
			(end -0.12065 -0.305054)
			(stroke
				(width 0.1)
				(type default)
			)
			(layer "F.Fab")
		)
		(fp_line
			(start -0.67945 0.3048)
			(end -0.67945 -0.305054)
			(stroke
				(width 0.1)
				(type default)
			)
			(layer "F.Fab")
		)
		(fp_line
			(start -0.12065 -0.305054)
			(end -0.12065 -0.2794)
			(stroke
				(width 0.1)
				(type default)
			)
			(layer "F.Fab")
		)
		(fp_line
			(start -0.12065 -0.2794)
			(end 0.12065 -0.2794)
			(stroke
				(width 0.1)
				(type default)
			)
			(layer "F.Fab")
		)
		(fp_line
			(start -0.12065 0.2794)
			(end -0.12065 0.3048)
			(stroke
				(width 0.1)
				(type default)
			)
			(layer "F.Fab")
		)
		(fp_line
			(start -0.12065 0.3048)
			(end -0.67945 0.3048)
			(stroke
				(width 0.1)
				(type default)
			)
			(layer "F.Fab")
		)
		(fp_line
			(start 0.120396 0.2794)
			(end -0.12065 0.2794)
			(stroke
				(width 0.1)
				(type default)
			)
			(layer "F.Fab")
		)
		(fp_line
			(start 0.120396 0.3048)
			(end 0.120396 0.2794)
			(stroke
				(width 0.1)
				(type default)
			)
			(layer "F.Fab")
		)
		(fp_line
			(start 0.12065 -0.3048)
			(end 0.67945 -0.3048)
			(stroke
				(width 0.1)
				(type default)
			)
			(layer "F.Fab")
		)
		(fp_line
			(start 0.12065 -0.2794)
			(end 0.12065 -0.3048)
			(stroke
				(width 0.1)
				(type default)
			)
			(layer "F.Fab")
		)
		(fp_line
			(start 0.67945 -0.3048)
			(end 0.67945 0.3048)
			(stroke
				(width 0.1)
				(type default)
			)
			(layer "F.Fab")
		)
		(fp_line
			(start 0.67945 0.3048)
			(end 0.120396 0.3048)
			(stroke
				(width 0.1)
				(type default)
			)
			(layer "F.Fab")
		)
		(pad "1" smd circle
			(at -0.40005 0)
			(size 0 0)
			(layers "F.Cu" "F.Mask" "F.Paste")
			(net "SMB_BMC_SWB_BUF_R_SCL")
		)
		(pad "2" smd circle
			(at 0.40005 0)
			(size 0 0)
			(layers "F.Cu" "F.Mask" "F.Paste")
			(net "SMB_BMC_SWB_BUF_SCL")
		)
	)
	(footprint ""
		(layer "F.Cu")
		(at 300.482762 -337.399122)
		(property "Reference" "PL17"
			(at -3.242056 -15.760446 0)
			(unlocked yes)
			(layer "F.SilkS")
			(effects
				(font
					(size 0.7874 0.5842)
					(thickness 0.1524)
				)
				(justify left)
			)
		)
		(property "Value" ""
			(at 0 0 0)
			(layer "F.Fab")
			(effects
				(font
					(size 1.27 1.27)
				)
			)
		)
		(duplicate_pad_numbers_are_jumpers no)
		(fp_line
			(start -3.750056 -5.500116)
			(end -2.393442 -5.500116)
			(stroke
				(width 0.1524)
				(type default)
			)
			(layer "F.SilkS")
		)
		(fp_line
			(start -3.750056 5.500116)
			(end -3.750056 -5.500116)
			(stroke
				(width 0.1524)
				(type default)
			)
			(layer "F.SilkS")
		)
		(fp_line
			(start -2.393442 5.500116)
			(end -3.750056 5.500116)
			(stroke
				(width 0.1524)
				(type default)
			)
			(layer "F.SilkS")
		)
		(fp_line
			(start 2.393442 5.500116)
			(end 3.750056 5.500116)
			(stroke
				(width 0.1524)
				(type default)
			)
			(layer "F.SilkS")
		)
		(fp_line
			(start 3.750056 -5.500116)
			(end 2.393442 -5.500116)
			(stroke
				(width 0.1524)
				(type default)
			)
			(layer "F.SilkS")
		)
		(fp_line
			(start 3.750056 5.500116)
			(end 3.750056 -5.500116)
			(stroke
				(width 0.1524)
				(type default)
			)
			(layer "F.SilkS")
		)
		(fp_poly
			(pts
				(xy -3.9116 -4.249928) (xy -4.3434 -4.034028) (xy -4.3434 -4.465828)
			)
			(stroke
				(width 0)
				(type default)
			)
			(fill yes)
			(layer "F.SilkS")
		)
		(fp_line
			(start -3.750056 -5.500116)
			(end -3.750056 5.500116)
			(stroke
				(width 0.1)
				(type default)
			)
			(layer "F.Fab")
		)
		(fp_line
			(start -3.750056 5.500116)
			(end 3.750056 5.500116)
			(stroke
				(width 0.1)
				(type default)
			)
			(layer "F.Fab")
		)
		(fp_line
			(start 3.750056 -5.500116)
			(end -3.750056 -5.500116)
			(stroke
				(width 0.1)
				(type default)
			)
			(layer "F.Fab")
		)
		(fp_line
			(start 3.750056 5.500116)
			(end 3.750056 -5.500116)
			(stroke
				(width 0.1)
				(type default)
			)
			(layer "F.Fab")
		)
		(fp_poly
			(pts
				(xy -4.9276 -4.757928) (xy -4.9276 -3.741928) (xy -3.9116 -4.249928)
			)
			(stroke
				(width 0)
				(type default)
			)
			(fill yes)
			(layer "F.Fab")
		)
		(pad "1" smd rect
			(at 0 -4.249928 270)
			(size 2.413 4.5212)
			(layers "F.Cu" "F.Mask" "F.Paste")
			(net "SW_PVDDIO_P0_SW1")
		)
		(pad "2" smd rect
			(at 0 -1.175004 270)
			(size 1.3716 4.5212)
			(layers "F.Cu" "F.Mask" "F.Paste")
			(net "IND_PVDDIO_P0_CPL2")
		)
		(pad "3" smd rect
			(at 0 1.175004 270)
			(size 1.3716 4.5212)
			(layers "F.Cu" "F.Mask" "F.Paste")
			(net "GND")
		)
		(pad "4" smd rect
			(at 0 4.249928 270)
			(size 2.413 4.5212)
			(layers "F.Cu" "F.Mask" "F.Paste")
			(net "PVDDIO_P0")
		)
	)
)
